FILE_TYPE = MULTI_PHYS_TABLE;

PART 'BAT54C'

{========================================================================================}
:VALUE    | PART_TYPE | MATERIAL | PART_NUMBER      = PART_NUMBER   | JEDEC_TYPE  | DESCRIPTION                           | MANUFTR | MANUF_PN | RD_CMPLS_LVL | CMPLS_LVL | CLASS | DIP_SMD | FP_ECN | FROM_PJ        | DATA               | EE_CHECK_LIST | STANDARD | PSL | PREFERENCE | LIFECYCLE | CREATOR | CREATEDAY    | STATUS ;
{========================================================================================}
 'BAT54C' | 'SMLF'    | 'IC'     | 'BCBAT54CZ04'(!) = 'BCBAT54CZ04' |'SOT23_123'| 'DIODE SMD BAT54C(30V,0.2A,SCHOTTKY)' | 'PJT'   | 'BAT54C' | 'EP(V1)'     | 'EP(V1)'  | 'IC'  | ''      | ''     | 'TU1D-MICHAEL' | 'BAT54_series.pdf' | ''            | 'End of Design'  | ''  | ''         | 'Comp-Approve'   | ''      | '20111020' | ''    
 'BAT54C' | 'SMLF'    | 'EMPTY'  | 'BCBAT54CZ04'(!) = 'BCBAT54CZ04' |'SOT23_123'| 'DIODE SMD BAT54C(30V,0.2A,SCHOTTKY)' | 'PJT'   | 'BAT54C' | 'EP(V1)'     | 'EP(V1)'  | 'IC'  | ''      | ''     | 'TU1D-MICHAEL' | 'BAT54_series.pdf' | ''            | 'End of Design'  | ''  | ''         | 'Comp-Approve'   | ''      | '20111020' | ''    

END_PART

END.

